# TIMECARD (Time Appliance Project (Time Card)) — schematic netlist excerpt (pin names and nets, part order shuffled) for the footprints in the layout excerpt that follows; sources: Cadence DE-HDL packaged netlist, KiCad conversion of R4006-B0001-02_R01.brd

C21  CAPACITOR  22UF 10V 20%  pkg SMC_0805R_H057  page 28 : \1\ = XP3R3V ; \2\ = SG
R276  RESISTOR  100OHM 1%  pkg SMC_0402R_H016  page 13 : \1\ = FPGA_OUT_MAC_PPS_IN0P ; \2\ = FPGA_OUT_MAC_PPS_IN0N

(kicad_pcb
	(version 20260206)
	(generator "pcbnew")
	(generator_version "10.0")
	(general
		(thickness 1.6)
		(legacy_teardrops no)
	)
	(paper "A4")
	(title_block
		(title "timecard-production-celestica-r4006 — R4006-B0001-02_R01.brd")
		(comment 1 "Time Appliance Project (Time Card) / footprints 114-115 of 1113")
	)
	(layers
		(0 "F.Cu" signal "TOP")
		(4 "In1.Cu" signal "L02_GND1")
		(6 "In2.Cu" signal "L03_SIG1")
		(8 "In3.Cu" signal "L04_GND2")
		(10 "In4.Cu" signal "L05_VCC1")
		(12 "In5.Cu" signal "L06_VCC2")
		(14 "In6.Cu" signal "L07_GND3")
		(16 "In7.Cu" signal "L08_SIG2")
		(18 "In8.Cu" signal "L09_GND4")
		(2 "B.Cu" signal "BOTTOM")
		(9 "F.Adhes" user "F.Adhesive")
		(11 "B.Adhes" user "B.Adhesive")
		(13 "F.Paste" user "Package Geometry/Pastemask Top")
		(15 "B.Paste" user "Package Geometry/Pastemask Bottom")
		(5 "F.SilkS" user "Ref Des/Silkscreen Top")
		(7 "B.SilkS" user "Ref Des/Silkscreen Bottom")
		(1 "F.Mask" user "Board Geometry/Soldermask Top")
		(3 "B.Mask" user "Board Geometry/Soldermask Bottom")
		(17 "Dwgs.User" user "User.Drawings")
		(19 "Cmts.User" user "User.Comments")
		(21 "Eco1.User" user "User.Eco1")
		(23 "Eco2.User" user "User.Eco2")
		(25 "Edge.Cuts" user "Board Geometry/Outline")
		(27 "Margin" user)
		(31 "F.CrtYd" user "Package Geometry/Place Bound Top")
		(29 "B.CrtYd" user "Package Geometry/Place Bound Bottom")
		(35 "F.Fab" user "Ref Des/Assembly Top")
		(33 "B.Fab" user "Ref Des/Assembly Bottom")
	)
	(footprint ""
		(layer "F.Cu")
		(at 84.328 -93.599 90)
		(property "Reference" "C21"
			(at -3.81 -3.89763 90)
			(unlocked yes)
			(layer "F.SilkS")
			(effects
				(font
					(size 0.7874 0.5842)
					(thickness 0.1524)
				)
			)
		)
		(property "Value" "VAL*"
			(at 0.0762 3.134106 90)
			(unlocked yes)
			(layer "F.Fab")
			(hide yes)
			(effects
				(font
					(size 0.7874 0.5842)
					(thickness 0.1524)
				)
			)
		)
		(property "Tolerance" "TOL*"
			(at 0.0762 4.048506 90)
			(unlocked yes)
			(layer "Cmts.User")
			(hide yes)
			(effects
				(font
					(size 0.7874 0.5842)
					(thickness 0.1524)
				)
			)
		)
		(property "User Part Number" "PARTNUM*"
			(at 0.1016 5.013706 90)
			(unlocked yes)
			(layer "Cmts.User")
			(hide yes)
			(effects
				(font
					(size 0.7874 0.5842)
					(thickness 0.1524)
				)
			)
		)
		(property "Device Type" "CAPACITOR-G107-0F226-CM,22UF,2A"
			(at 0.0508 2.194306 90)
			(unlocked yes)
			(layer "F.Fab")
			(hide yes)
			(effects
				(font
					(size 0.7874 0.5842)
					(thickness 0.1524)
				)
			)
		)
		(duplicate_pad_numbers_are_jumpers no)
		(fp_line
			(start 1.5748 -0.9398)
			(end -1.5748 -0.9398)
			(stroke
				(width 0.1)
				(type default)
			)
			(layer "F.SilkS")
		)
		(fp_line
			(start -1.5748 -0.9398)
			(end -1.5748 0.9398)
			(stroke
				(width 0.1)
				(type default)
			)
			(layer "F.SilkS")
		)
		(fp_line
			(start 1.5748 0.9398)
			(end 1.5748 -0.9398)
			(stroke
				(width 0.1)
				(type default)
			)
			(layer "F.SilkS")
		)
		(fp_line
			(start -1.5748 0.9398)
			(end 1.5748 0.9398)
			(stroke
				(width 0.1)
				(type default)
			)
			(layer "F.SilkS")
		)
		(fp_rect
			(start -1.5748 -0.9398)
			(end 1.5748 0.9398)
			(stroke
				(width 0)
				(type default)
			)
			(fill no)
			(layer "F.CrtYd")
		)
		(fp_line
			(start 1.016 -0.635)
			(end -1.016 -0.635)
			(stroke
				(width 0.1)
				(type default)
			)
			(layer "F.Fab")
		)
		(fp_line
			(start -1.016 -0.635)
			(end -1.016 0.635)
			(stroke
				(width 0.1)
				(type default)
			)
			(layer "F.Fab")
		)
		(fp_line
			(start 1.016 0.635)
			(end 1.016 -0.635)
			(stroke
				(width 0.1)
				(type default)
			)
			(layer "F.Fab")
		)
		(fp_line
			(start -1.016 0.635)
			(end 1.016 0.635)
			(stroke
				(width 0.1)
				(type default)
			)
			(layer "F.Fab")
		)
		(pad "1" smd rect
			(at -0.8382 0 90)
			(size 0.9652 1.3716)
			(layers "F.Cu" "F.Mask" "F.Paste")
			(net "XP3R3V")
		)
		(pad "2" smd rect
			(at 0.8382 0 90)
			(size 0.9652 1.3716)
			(layers "F.Cu" "F.Mask" "F.Paste")
			(net "SG")
		)
		(zone
			(layer "F.Cu")
			(hatch none 0.5)
			(connect_pads
				(clearance 0)
			)
			(min_thickness 0.25)
			(keepout
				(tracks allowed)
				(vias not_allowed)
				(pads allowed)
				(copperpour not_allowed)
				(footprints allowed)
			)
			(placement
				(enabled no)
				(sheetname "")
			)
			(fill
				(thermal_gap 0.5)
				(thermal_bridge_width 0.5)
				(island_removal_mode 0)
			)
			(polygon
				(pts
					(xy 83.693 -93.3704) (xy 84.963 -93.3704) (xy 84.963 -93.8276) (xy 83.693 -93.8276)
				)
			)
		)
	)
	(footprint ""
		(layer "F.Cu")
		(at 82.7786 -50.546 -90)
		(property "Reference" "R276"
			(at 14.478 1.09093 90)
			(unlocked yes)
			(layer "F.SilkS")
			(effects
				(font
					(size 0.7874 0.5842)
					(thickness 0.1524)
				)
			)
		)
		(property "Value" "VAL*"
			(at 0.02032 2.13233 270)
			(unlocked yes)
			(layer "F.Fab")
			(hide yes)
			(effects
				(font
					(size 0.7874 0.5842)
					(thickness 0.1524)
				)
			)
		)
		(property "Tolerance" "TOL*"
			(at 0.044704 3.05435 270)
			(unlocked yes)
			(layer "Cmts.User")
			(hide yes)
			(effects
				(font
					(size 0.7874 0.5842)
					(thickness 0.1524)
				)
			)
		)
		(property "User Part Number" "PARTNUM*"
			(at 0.02032 4.024884 270)
			(unlocked yes)
			(layer "Cmts.User")
			(hide yes)
			(effects
				(font
					(size 0.7874 0.5842)
					(thickness 0.1524)
				)
			)
		)
		(property "Device Type" "RESISTOR-G155-11000-01,100OHM,A"
			(at 0.008382 1.210564 270)
			(unlocked yes)
			(layer "F.Fab")
			(hide yes)
			(effects
				(font
					(size 0.7874 0.5842)
					(thickness 0.1524)
				)
			)
		)
		(duplicate_pad_numbers_are_jumpers no)
		(fp_line
			(start -1.143 0.5588)
			(end 1.143 0.5588)
			(stroke
				(width 0.1)
				(type default)
			)
			(layer "F.SilkS")
		)
		(fp_line
			(start 1.143 0.5588)
			(end 1.143 -0.5588)
			(stroke
				(width 0.1)
				(type default)
			)
			(layer "F.SilkS")
		)
		(fp_line
			(start -1.143 -0.5588)
			(end -1.143 0.5588)
			(stroke
				(width 0.1)
				(type default)
			)
			(layer "F.SilkS")
		)
		(fp_line
			(start 1.143 -0.5588)
			(end -1.143 -0.5588)
			(stroke
				(width 0.1)
				(type default)
			)
			(layer "F.SilkS")
		)
		(fp_rect
			(start 1.143 0.5588)
			(end -1.143 -0.5588)
			(stroke
				(width 0)
				(type default)
			)
			(fill no)
			(layer "F.CrtYd")
		)
		(fp_line
			(start -0.508 0.3048)
			(end 0.508 0.3048)
			(stroke
				(width 0.1)
				(type default)
			)
			(layer "F.Fab")
		)
		(fp_line
			(start 0.508 0.3048)
			(end 0.508 -0.3048)
			(stroke
				(width 0.1)
				(type default)
			)
			(layer "F.Fab")
		)
		(fp_line
			(start -0.508 -0.3048)
			(end -0.508 0.3048)
			(stroke
				(width 0.1)
				(type default)
			)
			(layer "F.Fab")
		)
		(fp_line
			(start 0.508 -0.3048)
			(end -0.508 -0.3048)
			(stroke
				(width 0.1)
				(type default)
			)
			(layer "F.Fab")
		)
		(pad "1" smd rect
			(at -0.5334 0 270)
			(size 0.7112 0.6096)
			(layers "F.Cu" "F.Mask" "F.Paste")
			(net "FPGA_OUT_MAC_PPS_IN0P")
		)
		(pad "2" smd rect
			(at 0.5334 0 270)
			(size 0.7112 0.6096)
			(layers "F.Cu" "F.Mask" "F.Paste")
			(net "FPGA_OUT_MAC_PPS_IN0N")
		)
		(zone
			(layer "F.Cu")
			(hatch none 0.5)
			(connect_pads
				(clearance 0)
			)
			(min_thickness 0.25)
			(keepout
				(tracks allowed)
				(vias not_allowed)
				(pads allowed)
				(copperpour not_allowed)
				(footprints allowed)
			)
			(placement
				(enabled no)
				(sheetname "")
			)
			(fill
				(thermal_gap 0.5)
				(thermal_bridge_width 0.5)
				(island_removal_mode 0)
			)
			(polygon
				(pts
					(xy 82.4738 -50.4698) (xy 83.0834 -50.4698) (xy 83.0834 -50.6222) (xy 82.4738 -50.6222)
				)
			)
		)
	)
)
